# T6G (Grand Teton) — schematic netlist excerpt (pin names and nets, part order shuffled) for the footprints in the layout excerpt that follows; sources: Cadence DE-HDL packaged netlist, KiCad conversion of 04192023_DAF0TMB3IC0_F0TG_MB_C_brd_V02_OCP.brd

R3264  Q_RES  0 5% EMPTY  pkg 0402LF  page 247 : A = HP_LVC3_OCP_V3_2_R_EN ; B = P3V3_OCP_V3_2_EN_R
L20  Q_INDUCTOR  FCM2012KF-601T/0.5A IND  pkg SMLF  page 182 : \1\ = P3V3_AUX ; \2\ = P3V3_9ZXL045_P0_VDD
R5016  Q_RES  1K 1% EMPTY  pkg 0402LF  page 159 : A = PVDD11_S3_P0 ; B = I3C_SCM_1_R_SCL

(kicad_pcb
	(version 20260206)
	(generator "pcbnew")
	(generator_version "10.0")
	(general
		(thickness 1.6)
		(legacy_teardrops no)
	)
	(paper "A4")
	(title_block
		(title "04192023_DAF0TMB3IC0_F0TG_MB_C_brd_V02_OCP.brd")
		(comment 1 "Grand Teton / footprints 286-288 of 8354")
	)
	(layers
		(0 "F.Cu" signal "TOP")
		(4 "In1.Cu" signal "GND")
		(6 "In2.Cu" signal "IN1")
		(8 "In3.Cu" signal "GND1")
		(10 "In4.Cu" signal "IN2")
		(12 "In5.Cu" signal "GND2")
		(14 "In6.Cu" signal "IN3")
		(16 "In7.Cu" signal "GND3")
		(18 "In8.Cu" signal "VCC")
		(20 "In9.Cu" signal "VCC1")
		(22 "In10.Cu" signal "GND4")
		(24 "In11.Cu" signal "IN4")
		(26 "In12.Cu" signal "GND5")
		(28 "In13.Cu" signal "IN5")
		(30 "In14.Cu" signal "GND6")
		(32 "In15.Cu" signal "IN6")
		(34 "In16.Cu" signal "GND7")
		(2 "B.Cu" signal "BOTTOM")
		(9 "F.Adhes" user "F.Adhesive")
		(11 "B.Adhes" user "B.Adhesive")
		(13 "F.Paste" user "Package Geometry/Pastemask Top")
		(15 "B.Paste" user "Package Geometry/Pastemask Bottom")
		(5 "F.SilkS" user "Ref Des/Silkscreen Top")
		(7 "B.SilkS" user "Ref Des/Silkscreen Bottom")
		(1 "F.Mask" user "Board Geometry/Soldermask Top")
		(3 "B.Mask" user "Board Geometry/Soldermask Bottom")
		(17 "Dwgs.User" user "User.Drawings")
		(19 "Cmts.User" user "User.Comments")
		(21 "Eco1.User" user "User.Eco1")
		(23 "Eco2.User" user "User.Eco2")
		(25 "Edge.Cuts" user "Board Geometry/Outline")
		(27 "Margin" user)
		(31 "F.CrtYd" user "Package Geometry/Place Bound Top")
		(29 "B.CrtYd" user "Package Geometry/Place Bound Bottom")
		(35 "F.Fab" user "Ref Des/Assembly Top")
		(33 "B.Fab" user "Ref Des/Assembly Bottom")
	)
	(footprint ""
		(layer "F.Cu")
		(at 152.849326 -35.97656)
		(property "Reference" "R3264"
			(at 0 0 0)
			(layer "F.SilkS")
			(hide yes)
			(effects
				(font
					(size 1.27 1.27)
				)
			)
		)
		(property "Value" ""
			(at 0 0 0)
			(layer "F.Fab")
			(effects
				(font
					(size 1.27 1.27)
				)
			)
		)
		(duplicate_pad_numbers_are_jumpers no)
		(fp_line
			(start -0.7874 -0.4064)
			(end 0.7874 -0.4064)
			(stroke
				(width 0.1524)
				(type default)
			)
			(layer "F.SilkS")
		)
		(fp_line
			(start -0.7874 0.4064)
			(end -0.7874 -0.4064)
			(stroke
				(width 0.1524)
				(type default)
			)
			(layer "F.SilkS")
		)
		(fp_line
			(start 0.7874 -0.4064)
			(end 0.7874 0.4064)
			(stroke
				(width 0.1524)
				(type default)
			)
			(layer "F.SilkS")
		)
		(fp_line
			(start 0.7874 0.4064)
			(end -0.7874 0.4064)
			(stroke
				(width 0.1524)
				(type default)
			)
			(layer "F.SilkS")
		)
		(fp_line
			(start -0.67945 -0.305054)
			(end -0.12065 -0.305054)
			(stroke
				(width 0.1)
				(type default)
			)
			(layer "F.Fab")
		)
		(fp_line
			(start -0.67945 0.3048)
			(end -0.67945 -0.305054)
			(stroke
				(width 0.1)
				(type default)
			)
			(layer "F.Fab")
		)
		(fp_line
			(start -0.12065 -0.305054)
			(end -0.12065 -0.2794)
			(stroke
				(width 0.1)
				(type default)
			)
			(layer "F.Fab")
		)
		(fp_line
			(start -0.12065 -0.2794)
			(end 0.12065 -0.2794)
			(stroke
				(width 0.1)
				(type default)
			)
			(layer "F.Fab")
		)
		(fp_line
			(start -0.12065 0.2794)
			(end -0.12065 0.3048)
			(stroke
				(width 0.1)
				(type default)
			)
			(layer "F.Fab")
		)
		(fp_line
			(start -0.12065 0.3048)
			(end -0.67945 0.3048)
			(stroke
				(width 0.1)
				(type default)
			)
			(layer "F.Fab")
		)
		(fp_line
			(start 0.120396 0.2794)
			(end -0.12065 0.2794)
			(stroke
				(width 0.1)
				(type default)
			)
			(layer "F.Fab")
		)
		(fp_line
			(start 0.120396 0.3048)
			(end 0.120396 0.2794)
			(stroke
				(width 0.1)
				(type default)
			)
			(layer "F.Fab")
		)
		(fp_line
			(start 0.12065 -0.3048)
			(end 0.67945 -0.3048)
			(stroke
				(width 0.1)
				(type default)
			)
			(layer "F.Fab")
		)
		(fp_line
			(start 0.12065 -0.2794)
			(end 0.12065 -0.3048)
			(stroke
				(width 0.1)
				(type default)
			)
			(layer "F.Fab")
		)
		(fp_line
			(start 0.67945 -0.3048)
			(end 0.67945 0.3048)
			(stroke
				(width 0.1)
				(type default)
			)
			(layer "F.Fab")
		)
		(fp_line
			(start 0.67945 0.3048)
			(end 0.120396 0.3048)
			(stroke
				(width 0.1)
				(type default)
			)
			(layer "F.Fab")
		)
		(pad "1" smd circle
			(at -0.40005 0)
			(size 0 0)
			(layers "F.Cu" "F.Mask" "F.Paste")
			(net "HP_LVC3_OCP_V3_2_R_EN")
		)
		(pad "2" smd circle
			(at 0.40005 0)
			(size 0 0)
			(layers "F.Cu" "F.Mask" "F.Paste")
			(net "P3V3_OCP_V3_2_EN_R")
		)
	)
	(footprint ""
		(layer "F.Cu")
		(at 442.233558 -168.710864 180)
		(property "Reference" "R5016"
			(at 0 0 180)
			(layer "F.SilkS")
			(hide yes)
			(effects
				(font
					(size 1.27 1.27)
				)
			)
		)
		(property "Value" ""
			(at 0 0 180)
			(layer "F.Fab")
			(effects
				(font
					(size 1.27 1.27)
				)
			)
		)
		(duplicate_pad_numbers_are_jumpers no)
		(fp_line
			(start 0.7874 0.4064)
			(end -0.7874 0.4064)
			(stroke
				(width 0.1524)
				(type default)
			)
			(layer "F.SilkS")
		)
		(fp_line
			(start 0.7874 -0.4064)
			(end 0.7874 0.4064)
			(stroke
				(width 0.1524)
				(type default)
			)
			(layer "F.SilkS")
		)
		(fp_line
			(start -0.7874 0.4064)
			(end -0.7874 -0.4064)
			(stroke
				(width 0.1524)
				(type default)
			)
			(layer "F.SilkS")
		)
		(fp_line
			(start -0.7874 -0.4064)
			(end 0.7874 -0.4064)
			(stroke
				(width 0.1524)
				(type default)
			)
			(layer "F.SilkS")
		)
		(fp_line
			(start 0.67945 0.3048)
			(end 0.120396 0.3048)
			(stroke
				(width 0.1)
				(type default)
			)
			(layer "F.Fab")
		)
		(fp_line
			(start 0.67945 -0.3048)
			(end 0.67945 0.3048)
			(stroke
				(width 0.1)
				(type default)
			)
			(layer "F.Fab")
		)
		(fp_line
			(start 0.12065 -0.2794)
			(end 0.12065 -0.3048)
			(stroke
				(width 0.1)
				(type default)
			)
			(layer "F.Fab")
		)
		(fp_line
			(start 0.12065 -0.3048)
			(end 0.67945 -0.3048)
			(stroke
				(width 0.1)
				(type default)
			)
			(layer "F.Fab")
		)
		(fp_line
			(start 0.120396 0.3048)
			(end 0.120396 0.2794)
			(stroke
				(width 0.1)
				(type default)
			)
			(layer "F.Fab")
		)
		(fp_line
			(start 0.120396 0.2794)
			(end -0.12065 0.2794)
			(stroke
				(width 0.1)
				(type default)
			)
			(layer "F.Fab")
		)
		(fp_line
			(start -0.12065 0.3048)
			(end -0.67945 0.3048)
			(stroke
				(width 0.1)
				(type default)
			)
			(layer "F.Fab")
		)
		(fp_line
			(start -0.12065 0.2794)
			(end -0.12065 0.3048)
			(stroke
				(width 0.1)
				(type default)
			)
			(layer "F.Fab")
		)
		(fp_line
			(start -0.12065 -0.2794)
			(end 0.12065 -0.2794)
			(stroke
				(width 0.1)
				(type default)
			)
			(layer "F.Fab")
		)
		(fp_line
			(start -0.12065 -0.305054)
			(end -0.12065 -0.2794)
			(stroke
				(width 0.1)
				(type default)
			)
			(layer "F.Fab")
		)
		(fp_line
			(start -0.67945 0.3048)
			(end -0.67945 -0.305054)
			(stroke
				(width 0.1)
				(type default)
			)
			(layer "F.Fab")
		)
		(fp_line
			(start -0.67945 -0.305054)
			(end -0.12065 -0.305054)
			(stroke
				(width 0.1)
				(type default)
			)
			(layer "F.Fab")
		)
		(pad "1" smd circle
			(at -0.40005 0 180)
			(size 0 0)
			(layers "F.Cu" "F.Mask" "F.Paste")
			(net "PVDD11_S3_P0")
		)
		(pad "2" smd circle
			(at 0.40005 0 180)
			(size 0 0)
			(layers "F.Cu" "F.Mask" "F.Paste")
			(net "I3C_SCM_1_R_SCL")
		)
	)
	(footprint ""
		(layer "F.Cu")
		(at 281.659076 -412.452058 90)
		(property "Reference" "L20"
			(at 0 0 90)
			(layer "F.SilkS")
			(hide yes)
			(effects
				(font
					(size 1.27 1.27)
				)
			)
		)
		(property "Value" ""
			(at 0 0 90)
			(layer "F.Fab")
			(effects
				(font
					(size 1.27 1.27)
				)
			)
		)
		(duplicate_pad_numbers_are_jumpers no)
		(fp_line
			(start 1.63576 -0.8128)
			(end 1.63576 0.8128)
			(stroke
				(width 0.1524)
				(type default)
			)
			(layer "F.SilkS")
		)
		(fp_line
			(start -1.63576 -0.8128)
			(end 1.63576 -0.8128)
			(stroke
				(width 0.1524)
				(type default)
			)
			(layer "F.SilkS")
		)
		(fp_line
			(start -1.63576 -0.8128)
			(end -1.63576 0.8128)
			(stroke
				(width 0.1524)
				(type default)
			)
			(layer "F.SilkS")
		)
		(fp_line
			(start 1.63576 0.8128)
			(end -1.63576 0.8128)
			(stroke
				(width 0.1524)
				(type default)
			)
			(layer "F.SilkS")
		)
		(fp_line
			(start 1.560576 -0.738632)
			(end -1.56083 -0.738632)
			(stroke
				(width 0.1)
				(type default)
			)
			(layer "F.Fab")
		)
		(fp_line
			(start -1.56083 -0.738632)
			(end -1.56083 0.7366)
			(stroke
				(width 0.1)
				(type default)
			)
			(layer "F.Fab")
		)
		(fp_line
			(start 1.560576 0.7366)
			(end 1.560576 -0.738632)
			(stroke
				(width 0.1)
				(type default)
			)
			(layer "F.Fab")
		)
		(fp_line
			(start 1.524 0.7366)
			(end 1.560576 0.7366)
			(stroke
				(width 0.1)
				(type default)
			)
			(layer "F.Fab")
		)
		(fp_line
			(start -1.524 0.7366)
			(end 1.524 0.7366)
			(stroke
				(width 0.1)
				(type default)
			)
			(layer "F.Fab")
		)
		(fp_line
			(start -1.56083 0.7366)
			(end -1.524 0.7366)
			(stroke
				(width 0.1)
				(type default)
			)
			(layer "F.Fab")
		)
		(pad "1" smd rect
			(at -0.94996 0 270)
			(size 1.1176 1.3716)
			(layers "F.Cu" "F.Mask" "F.Paste")
			(net "P3V3_AUX")
		)
		(pad "2" smd rect
			(at 0.94996 0 270)
			(size 1.1176 1.3716)
			(layers "F.Cu" "F.Mask" "F.Paste")
			(net "P3V3_9ZXL045_P0_VDD")
		)
	)
)
